(kicad_pcb
	(version 20260206)
	(generator "pcbnew")
	(generator_version "10.0")
	(general
		(thickness 1.6)
		(legacy_teardrops no)
	)
	(paper "A4")
	(title_block
		(title "01162023_DA0F0TEBIF0_F0T_Expander_BD_F_brd_V02_OCP.brd")
		(comment 1 "Grand Teton / footprints 2898-2904 of 9728")
	)
	(layers
		(0 "F.Cu" signal "TOP")
		(4 "In1.Cu" signal "GND")
		(6 "In2.Cu" signal "VCC")
		(8 "In3.Cu" signal "VCC1")
		(10 "In4.Cu" signal "GND1")
		(12 "In5.Cu" signal "IN1")
		(14 "In6.Cu" signal "GND2")
		(16 "In7.Cu" signal "IN2")
		(18 "In8.Cu" signal "GND3")
		(20 "In9.Cu" signal "IN3")
		(22 "In10.Cu" signal "GND4")
		(24 "In11.Cu" signal "IN4")
		(26 "In12.Cu" signal "GND5")
		(28 "In13.Cu" signal "IN5")
		(30 "In14.Cu" signal "GND6")
		(32 "In15.Cu" signal "IN6")
		(34 "In16.Cu" signal "GND7")
		(2 "B.Cu" signal "BOTTOM")
		(9 "F.Adhes" user "F.Adhesive")
		(11 "B.Adhes" user "B.Adhesive")
		(13 "F.Paste" user "Package Geometry/Pastemask Top")
		(15 "B.Paste" user "Package Geometry/Pastemask Bottom")
		(5 "F.SilkS" user "Ref Des/Silkscreen Top")
		(7 "B.SilkS" user "Ref Des/Silkscreen Bottom")
		(1 "F.Mask" user "Board Geometry/Soldermask Top")
		(3 "B.Mask" user "Board Geometry/Soldermask Bottom")
		(17 "Dwgs.User" user "User.Drawings")
		(19 "Cmts.User" user "User.Comments")
		(21 "Eco1.User" user "User.Eco1")
		(23 "Eco2.User" user "User.Eco2")
		(25 "Edge.Cuts" user "Board Geometry/Outline")
		(27 "Margin" user)
		(31 "F.CrtYd" user "Package Geometry/Place Bound Top")
		(29 "B.CrtYd" user "Package Geometry/Place Bound Bottom")
		(35 "F.Fab" user "Ref Des/Assembly Top")
		(33 "B.Fab" user "Ref Des/Assembly Bottom")
	)
	(footprint ""
		(layer "F.Cu")
		(at 14.207998 -170.632628 180)
		(property "Reference" "PL2"
			(at 3.438398 -4.162298 0)
			(unlocked yes)
			(layer "F.SilkS")
			(effects
				(font
					(size 0.7874 0.5842)
					(thickness 0.1524)
				)
				(justify left)
			)
		)
		(property "Value" ""
			(at 0 0 180)
			(layer "F.Fab")
			(effects
				(font
					(size 1.27 1.27)
				)
			)
		)
		(duplicate_pad_numbers_are_jumpers no)
		(fp_line
			(start 3.400044 3.400044)
			(end -3.400044 3.400044)
			(stroke
				(width 0.1524)
				(type default)
			)
			(layer "F.SilkS")
		)
		(fp_line
			(start 3.400044 1.8923)
			(end 3.400044 3.400044)
			(stroke
				(width 0.1524)
				(type default)
			)
			(layer "F.SilkS")
		)
		(fp_line
			(start 3.400044 -3.400044)
			(end 3.400044 -1.8923)
			(stroke
				(width 0.1524)
				(type default)
			)
			(layer "F.SilkS")
		)
		(fp_line
			(start -3.400044 3.400044)
			(end -3.400044 1.8923)
			(stroke
				(width 0.1524)
				(type default)
			)
			(layer "F.SilkS")
		)
		(fp_line
			(start -3.400044 -1.8923)
			(end -3.400044 -3.400044)
			(stroke
				(width 0.1524)
				(type default)
			)
			(layer "F.SilkS")
		)
		(fp_line
			(start -3.400044 -3.400044)
			(end 3.400044 -3.400044)
			(stroke
				(width 0.1524)
				(type default)
			)
			(layer "F.SilkS")
		)
		(fp_line
			(start 3.400044 3.400044)
			(end -3.400044 3.400044)
			(stroke
				(width 0.1)
				(type default)
			)
			(layer "F.Fab")
		)
		(fp_line
			(start 3.400044 -3.400044)
			(end 3.400044 3.400044)
			(stroke
				(width 0.1)
				(type default)
			)
			(layer "F.Fab")
		)
		(fp_line
			(start -3.400044 3.400044)
			(end -3.400044 -3.400044)
			(stroke
				(width 0.1)
				(type default)
			)
			(layer "F.Fab")
		)
		(fp_line
			(start -3.400044 -3.400044)
			(end 3.400044 -3.400044)
			(stroke
				(width 0.1)
				(type default)
			)
			(layer "F.Fab")
		)
		(pad "1" smd rect
			(at -2.77495 0 180)
			(size 1.8542 3.5052)
			(layers "F.Cu" "F.Mask" "F.Paste")
			(net "SW_P5V_AUX_PH")
		)
		(pad "2" smd rect
			(at 2.77495 0 180)
			(size 1.8542 3.5052)
			(layers "F.Cu" "F.Mask" "F.Paste")
			(net "P5V_AUX")
		)
	)
	(footprint ""
		(layer "F.Cu")
		(at 215.075516 -119.223028)
		(property "Reference" "R4480"
			(at 0 0 0)
			(layer "F.SilkS")
			(hide yes)
			(effects
				(font
					(size 1.27 1.27)
				)
			)
		)
		(property "Value" ""
			(at 0 0 0)
			(layer "F.Fab")
			(effects
				(font
					(size 1.27 1.27)
				)
			)
		)
		(duplicate_pad_numbers_are_jumpers no)
		(fp_line
			(start -0.7874 -0.4064)
			(end 0.7874 -0.4064)
			(stroke
				(width 0.1524)
				(type default)
			)
			(layer "F.SilkS")
		)
		(fp_line
			(start -0.7874 0.4064)
			(end -0.7874 -0.4064)
			(stroke
				(width 0.1524)
				(type default)
			)
			(layer "F.SilkS")
		)
		(fp_line
			(start 0.7874 -0.4064)
			(end 0.7874 0.4064)
			(stroke
				(width 0.1524)
				(type default)
			)
			(layer "F.SilkS")
		)
		(fp_line
			(start 0.7874 0.4064)
			(end -0.7874 0.4064)
			(stroke
				(width 0.1524)
				(type default)
			)
			(layer "F.SilkS")
		)
		(fp_line
			(start -0.67945 -0.305054)
			(end -0.12065 -0.305054)
			(stroke
				(width 0.1)
				(type default)
			)
			(layer "F.Fab")
		)
		(fp_line
			(start -0.67945 0.3048)
			(end -0.67945 -0.305054)
			(stroke
				(width 0.1)
				(type default)
			)
			(layer "F.Fab")
		)
		(fp_line
			(start -0.12065 -0.305054)
			(end -0.12065 -0.2794)
			(stroke
				(width 0.1)
				(type default)
			)
			(layer "F.Fab")
		)
		(fp_line
			(start -0.12065 -0.2794)
			(end 0.12065 -0.2794)
			(stroke
				(width 0.1)
				(type default)
			)
			(layer "F.Fab")
		)
		(fp_line
			(start -0.12065 0.2794)
			(end -0.12065 0.3048)
			(stroke
				(width 0.1)
				(type default)
			)
			(layer "F.Fab")
		)
		(fp_line
			(start -0.12065 0.3048)
			(end -0.67945 0.3048)
			(stroke
				(width 0.1)
				(type default)
			)
			(layer "F.Fab")
		)
		(fp_line
			(start 0.120396 0.2794)
			(end -0.12065 0.2794)
			(stroke
				(width 0.1)
				(type default)
			)
			(layer "F.Fab")
		)
		(fp_line
			(start 0.120396 0.3048)
			(end 0.120396 0.2794)
			(stroke
				(width 0.1)
				(type default)
			)
			(layer "F.Fab")
		)
		(fp_line
			(start 0.12065 -0.3048)
			(end 0.67945 -0.3048)
			(stroke
				(width 0.1)
				(type default)
			)
			(layer "F.Fab")
		)
		(fp_line
			(start 0.12065 -0.2794)
			(end 0.12065 -0.3048)
			(stroke
				(width 0.1)
				(type default)
			)
			(layer "F.Fab")
		)
		(fp_line
			(start 0.67945 -0.3048)
			(end 0.67945 0.3048)
			(stroke
				(width 0.1)
				(type default)
			)
			(layer "F.Fab")
		)
		(fp_line
			(start 0.67945 0.3048)
			(end 0.120396 0.3048)
			(stroke
				(width 0.1)
				(type default)
			)
			(layer "F.Fab")
		)
		(pad "1" smd circle
			(at -0.40005 0)
			(size 0 0)
			(layers "F.Cu" "F.Mask" "F.Paste")
			(net "PWRGD_P3V3_NIC3")
		)
		(pad "2" smd circle
			(at 0.40005 0)
			(size 0 0)
			(layers "F.Cu" "F.Mask" "F.Paste")
			(net "PWRGD_P3V3_NIC3_R")
		)
	)
	(footprint ""
		(layer "F.Cu")
		(at 425.407582 -81.09966)
		(property "Reference" "Q8"
			(at -1.989582 -1.75387 0)
			(unlocked yes)
			(layer "F.SilkS")
			(effects
				(font
					(size 0.7874 0.5842)
					(thickness 0.1524)
				)
				(justify left)
			)
		)
		(property "Value" ""
			(at 0 0 0)
			(layer "F.Fab")
			(effects
				(font
					(size 1.27 1.27)
				)
			)
		)
		(duplicate_pad_numbers_are_jumpers no)
		(fp_line
			(start -1.38176 -1.100074)
			(end -1.38176 1.100074)
			(stroke
				(width 0.1524)
				(type default)
			)
			(layer "F.SilkS")
		)
		(fp_line
			(start -1.38176 1.100074)
			(end 1.38176 1.100074)
			(stroke
				(width 0.1524)
				(type default)
			)
			(layer "F.SilkS")
		)
		(fp_line
			(start -0.592074 -1.100074)
			(end -1.38176 -1.100074)
			(stroke
				(width 0.1524)
				(type default)
			)
			(layer "F.SilkS")
		)
		(fp_line
			(start 0 -0.508)
			(end -0.592074 -1.100074)
			(stroke
				(width 0.1524)
				(type default)
			)
			(layer "F.SilkS")
		)
		(fp_line
			(start 0.592074 -1.100074)
			(end 0 -0.508)
			(stroke
				(width 0.1524)
				(type default)
			)
			(layer "F.SilkS")
		)
		(fp_line
			(start 1.38176 -1.100074)
			(end 0.592074 -1.100074)
			(stroke
				(width 0.1524)
				(type default)
			)
			(layer "F.SilkS")
		)
		(fp_line
			(start 1.38176 1.100074)
			(end 1.38176 -1.100074)
			(stroke
				(width 0.1524)
				(type default)
			)
			(layer "F.SilkS")
		)
		(fp_poly
			(pts
				(xy -1.9431 -0.870204) (xy -1.50241 -0.649986) (xy -1.9431 -0.429768)
			)
			(stroke
				(width 0)
				(type default)
			)
			(fill yes)
			(layer "F.SilkS")
		)
		(fp_line
			(start -0.674878 -1.100074)
			(end -0.674878 1.100074)
			(stroke
				(width 0.1)
				(type default)
			)
			(layer "F.Fab")
		)
		(fp_line
			(start -0.674878 1.100074)
			(end 0.674878 1.100074)
			(stroke
				(width 0.1)
				(type default)
			)
			(layer "F.Fab")
		)
		(fp_line
			(start 0.674878 -1.100074)
			(end -0.674878 -1.100074)
			(stroke
				(width 0.1)
				(type default)
			)
			(layer "F.Fab")
		)
		(fp_line
			(start 0.674878 1.100074)
			(end 0.674878 -1.100074)
			(stroke
				(width 0.1)
				(type default)
			)
			(layer "F.Fab")
		)
		(fp_poly
			(pts
				(xy -1.9431 -0.870204) (xy -1.50241 -0.649986) (xy -1.9431 -0.429768)
			)
			(stroke
				(width 0)
				(type default)
			)
			(fill yes)
			(layer "F.Fab")
		)
		(pad "1" smd rect
			(at -0.94996 -0.649986 270)
			(size 0.4318 0.6096)
			(layers "F.Cu" "F.Mask" "F.Paste")
			(net "GND")
		)
		(pad "2" smd rect
			(at -0.94996 0 270)
			(size 0.4318 0.6096)
			(layers "F.Cu" "F.Mask" "F.Paste")
			(net "HP_NIC7_HSC_PWRGD_N")
		)
		(pad "3" smd rect
			(at -0.94996 0.649986 270)
			(size 0.4318 0.6096)
			(layers "F.Cu" "F.Mask" "F.Paste")
			(net "HP_NIC7_HSC_PWRGD_N")
		)
		(pad "4" smd rect
			(at 0.94996 0.649986 270)
			(size 0.4318 0.6096)
			(layers "F.Cu" "F.Mask" "F.Paste")
			(net "GND")
		)
		(pad "5" smd rect
			(at 0.94996 0 270)
			(size 0.4318 0.6096)
			(layers "F.Cu" "F.Mask" "F.Paste")
			(net "PWRGD_P12V_NIC7_R")
		)
		(pad "6" smd rect
			(at 0.94996 -0.649986 270)
			(size 0.4318 0.6096)
			(layers "F.Cu" "F.Mask" "F.Paste")
			(net "HP_NIC7_PWRGD_R")
		)
	)
	(footprint ""
		(layer "F.Cu")
		(at 159.892492 -31.825184 180)
		(property "Reference" "C287"
			(at 0 0 180)
			(layer "F.SilkS")
			(hide yes)
			(effects
				(font
					(size 1.27 1.27)
				)
			)
		)
		(property "Value" ""
			(at 0 0 180)
			(layer "F.Fab")
			(effects
				(font
					(size 1.27 1.27)
				)
			)
		)
		(duplicate_pad_numbers_are_jumpers no)
		(fp_line
			(start 0.299974 0.150114)
			(end -0.299974 0.150114)
			(stroke
				(width 0.1)
				(type default)
			)
			(layer "F.Fab")
		)
		(fp_line
			(start 0.299974 -0.150114)
			(end 0.299974 0.150114)
			(stroke
				(width 0.1)
				(type default)
			)
			(layer "F.Fab")
		)
		(fp_line
			(start -0.299974 0.150114)
			(end -0.299974 -0.150114)
			(stroke
				(width 0.1)
				(type default)
			)
			(layer "F.Fab")
		)
		(fp_line
			(start -0.299974 -0.150114)
			(end 0.299974 -0.150114)
			(stroke
				(width 0.1)
				(type default)
			)
			(layer "F.Fab")
		)
		(pad "1" smd rect
			(at -0.2667 0 180)
			(size 0.3048 0.381)
			(layers "F.Cu" "F.Mask" "F.Paste")
			(net "P5E_PEX1_STN2_TX_DN<42>")
		)
		(pad "2" smd rect
			(at 0.2667 0 180)
			(size 0.3048 0.381)
			(layers "F.Cu" "F.Mask" "F.Paste")
			(net "P5E_PEX1_STN2_TX_C_DN<42>")
		)
	)
	(footprint ""
		(layer "F.Cu")
		(at 295.670732 -138.864848)
		(property "Reference" "R295"
			(at 0 0 0)
			(layer "F.SilkS")
			(hide yes)
			(effects
				(font
					(size 1.27 1.27)
				)
			)
		)
		(property "Value" ""
			(at 0 0 0)
			(layer "F.Fab")
			(effects
				(font
					(size 1.27 1.27)
				)
			)
		)
		(duplicate_pad_numbers_are_jumpers no)
		(fp_line
			(start -0.7874 -0.4064)
			(end 0.7874 -0.4064)
			(stroke
				(width 0.1524)
				(type default)
			)
			(layer "F.SilkS")
		)
		(fp_line
			(start -0.7874 0.4064)
			(end -0.7874 -0.4064)
			(stroke
				(width 0.1524)
				(type default)
			)
			(layer "F.SilkS")
		)
		(fp_line
			(start 0.7874 -0.4064)
			(end 0.7874 0.4064)
			(stroke
				(width 0.1524)
				(type default)
			)
			(layer "F.SilkS")
		)
		(fp_line
			(start 0.7874 0.4064)
			(end -0.7874 0.4064)
			(stroke
				(width 0.1524)
				(type default)
			)
			(layer "F.SilkS")
		)
		(fp_line
			(start -0.67945 -0.305054)
			(end -0.12065 -0.305054)
			(stroke
				(width 0.1)
				(type default)
			)
			(layer "F.Fab")
		)
		(fp_line
			(start -0.67945 0.3048)
			(end -0.67945 -0.305054)
			(stroke
				(width 0.1)
				(type default)
			)
			(layer "F.Fab")
		)
		(fp_line
			(start -0.12065 -0.305054)
			(end -0.12065 -0.2794)
			(stroke
				(width 0.1)
				(type default)
			)
			(layer "F.Fab")
		)
		(fp_line
			(start -0.12065 -0.2794)
			(end 0.12065 -0.2794)
			(stroke
				(width 0.1)
				(type default)
			)
			(layer "F.Fab")
		)
		(fp_line
			(start -0.12065 0.2794)
			(end -0.12065 0.3048)
			(stroke
				(width 0.1)
				(type default)
			)
			(layer "F.Fab")
		)
		(fp_line
			(start -0.12065 0.3048)
			(end -0.67945 0.3048)
			(stroke
				(width 0.1)
				(type default)
			)
			(layer "F.Fab")
		)
		(fp_line
			(start 0.120396 0.2794)
			(end -0.12065 0.2794)
			(stroke
				(width 0.1)
				(type default)
			)
			(layer "F.Fab")
		)
		(fp_line
			(start 0.120396 0.3048)
			(end 0.120396 0.2794)
			(stroke
				(width 0.1)
				(type default)
			)
			(layer "F.Fab")
		)
		(fp_line
			(start 0.12065 -0.3048)
			(end 0.67945 -0.3048)
			(stroke
				(width 0.1)
				(type default)
			)
			(layer "F.Fab")
		)
		(fp_line
			(start 0.12065 -0.2794)
			(end 0.12065 -0.3048)
			(stroke
				(width 0.1)
				(type default)
			)
			(layer "F.Fab")
		)
		(fp_line
			(start 0.67945 -0.3048)
			(end 0.67945 0.3048)
			(stroke
				(width 0.1)
				(type default)
			)
			(layer "F.Fab")
		)
		(fp_line
			(start 0.67945 0.3048)
			(end 0.120396 0.3048)
			(stroke
				(width 0.1)
				(type default)
			)
			(layer "F.Fab")
		)
		(pad "1" smd circle
			(at -0.40005 0)
			(size 0 0)
			(layers "F.Cu" "F.Mask" "F.Paste")
			(net "PRSNT_NIC5_N")
		)
		(pad "2" smd circle
			(at 0.40005 0)
			(size 0 0)
			(layers "F.Cu" "F.Mask" "F.Paste")
			(net "PRSNTB1_NIC5_N")
		)
	)
	(footprint ""
		(layer "F.Cu")
		(at 322.65366 -232.397046)
		(property "Reference" "R5647"
			(at 0 0 0)
			(layer "F.SilkS")
			(hide yes)
			(effects
				(font
					(size 1.27 1.27)
				)
			)
		)
		(property "Value" ""
			(at 0 0 0)
			(layer "F.Fab")
			(effects
				(font
					(size 1.27 1.27)
				)
			)
		)
		(duplicate_pad_numbers_are_jumpers no)
		(fp_line
			(start -0.7874 -0.4064)
			(end 0.7874 -0.4064)
			(stroke
				(width 0.1524)
				(type default)
			)
			(layer "F.SilkS")
		)
		(fp_line
			(start -0.7874 0.4064)
			(end -0.7874 -0.4064)
			(stroke
				(width 0.1524)
				(type default)
			)
			(layer "F.SilkS")
		)
		(fp_line
			(start 0.7874 -0.4064)
			(end 0.7874 0.4064)
			(stroke
				(width 0.1524)
				(type default)
			)
			(layer "F.SilkS")
		)
		(fp_line
			(start 0.7874 0.4064)
			(end -0.7874 0.4064)
			(stroke
				(width 0.1524)
				(type default)
			)
			(layer "F.SilkS")
		)
		(fp_line
			(start -0.67945 -0.305054)
			(end -0.12065 -0.305054)
			(stroke
				(width 0.1)
				(type default)
			)
			(layer "F.Fab")
		)
		(fp_line
			(start -0.67945 0.3048)
			(end -0.67945 -0.305054)
			(stroke
				(width 0.1)
				(type default)
			)
			(layer "F.Fab")
		)
		(fp_line
			(start -0.12065 -0.305054)
			(end -0.12065 -0.2794)
			(stroke
				(width 0.1)
				(type default)
			)
			(layer "F.Fab")
		)
		(fp_line
			(start -0.12065 -0.2794)
			(end 0.12065 -0.2794)
			(stroke
				(width 0.1)
				(type default)
			)
			(layer "F.Fab")
		)
		(fp_line
			(start -0.12065 0.2794)
			(end -0.12065 0.3048)
			(stroke
				(width 0.1)
				(type default)
			)
			(layer "F.Fab")
		)
		(fp_line
			(start -0.12065 0.3048)
			(end -0.67945 0.3048)
			(stroke
				(width 0.1)
				(type default)
			)
			(layer "F.Fab")
		)
		(fp_line
			(start 0.120396 0.2794)
			(end -0.12065 0.2794)
			(stroke
				(width 0.1)
				(type default)
			)
			(layer "F.Fab")
		)
		(fp_line
			(start 0.120396 0.3048)
			(end 0.120396 0.2794)
			(stroke
				(width 0.1)
				(type default)
			)
			(layer "F.Fab")
		)
		(fp_line
			(start 0.12065 -0.3048)
			(end 0.67945 -0.3048)
			(stroke
				(width 0.1)
				(type default)
			)
			(layer "F.Fab")
		)
		(fp_line
			(start 0.12065 -0.2794)
			(end 0.12065 -0.3048)
			(stroke
				(width 0.1)
				(type default)
			)
			(layer "F.Fab")
		)
		(fp_line
			(start 0.67945 -0.3048)
			(end 0.67945 0.3048)
			(stroke
				(width 0.1)
				(type default)
			)
			(layer "F.Fab")
		)
		(fp_line
			(start 0.67945 0.3048)
			(end 0.120396 0.3048)
			(stroke
				(width 0.1)
				(type default)
			)
			(layer "F.Fab")
		)
		(pad "1" smd circle
			(at -0.40005 0)
			(size 0 0)
			(layers "F.Cu" "F.Mask" "F.Paste")
			(net "SMB_MB_R_SDA")
		)
		(pad "2" smd circle
			(at 0.40005 0)
			(size 0 0)
			(layers "F.Cu" "F.Mask" "F.Paste")
			(net "SMB_MB_BMC_ISO_FPGA_SDA")
		)
	)
	(footprint ""
		(layer "F.Cu")
		(at 336.042 -186.055)
		(property "Reference" "R4736"
			(at 0 0 0)
			(layer "F.SilkS")
			(hide yes)
			(effects
				(font
					(size 1.27 1.27)
				)
			)
		)
		(property "Value" ""
			(at 0 0 0)
			(layer "F.Fab")
			(effects
				(font
					(size 1.27 1.27)
				)
			)
		)
		(duplicate_pad_numbers_are_jumpers no)
		(fp_line
			(start -0.7874 -0.4064)
			(end 0.7874 -0.4064)
			(stroke
				(width 0.1524)
				(type default)
			)
			(layer "F.SilkS")
		)
		(fp_line
			(start -0.7874 0.4064)
			(end -0.7874 -0.4064)
			(stroke
				(width 0.1524)
				(type default)
			)
			(layer "F.SilkS")
		)
		(fp_line
			(start 0.7874 -0.4064)
			(end 0.7874 0.4064)
			(stroke
				(width 0.1524)
				(type default)
			)
			(layer "F.SilkS")
		)
		(fp_line
			(start 0.7874 0.4064)
			(end -0.7874 0.4064)
			(stroke
				(width 0.1524)
				(type default)
			)
			(layer "F.SilkS")
		)
		(fp_line
			(start -0.67945 -0.305054)
			(end -0.12065 -0.305054)
			(stroke
				(width 0.1)
				(type default)
			)
			(layer "F.Fab")
		)
		(fp_line
			(start -0.67945 0.3048)
			(end -0.67945 -0.305054)
			(stroke
				(width 0.1)
				(type default)
			)
			(layer "F.Fab")
		)
		(fp_line
			(start -0.12065 -0.305054)
			(end -0.12065 -0.2794)
			(stroke
				(width 0.1)
				(type default)
			)
			(layer "F.Fab")
		)
		(fp_line
			(start -0.12065 -0.2794)
			(end 0.12065 -0.2794)
			(stroke
				(width 0.1)
				(type default)
			)
			(layer "F.Fab")
		)
		(fp_line
			(start -0.12065 0.2794)
			(end -0.12065 0.3048)
			(stroke
				(width 0.1)
				(type default)
			)
			(layer "F.Fab")
		)
		(fp_line
			(start -0.12065 0.3048)
			(end -0.67945 0.3048)
			(stroke
				(width 0.1)
				(type default)
			)
			(layer "F.Fab")
		)
		(fp_line
			(start 0.120396 0.2794)
			(end -0.12065 0.2794)
			(stroke
				(width 0.1)
				(type default)
			)
			(layer "F.Fab")
		)
		(fp_line
			(start 0.120396 0.3048)
			(end 0.120396 0.2794)
			(stroke
				(width 0.1)
				(type default)
			)
			(layer "F.Fab")
		)
		(fp_line
			(start 0.12065 -0.3048)
			(end 0.67945 -0.3048)
			(stroke
				(width 0.1)
				(type default)
			)
			(layer "F.Fab")
		)
		(fp_line
			(start 0.12065 -0.2794)
			(end 0.12065 -0.3048)
			(stroke
				(width 0.1)
				(type default)
			)
			(layer "F.Fab")
		)
		(fp_line
			(start 0.67945 -0.3048)
			(end 0.67945 0.3048)
			(stroke
				(width 0.1)
				(type default)
			)
			(layer "F.Fab")
		)
		(fp_line
			(start 0.67945 0.3048)
			(end 0.120396 0.3048)
			(stroke
				(width 0.1)
				(type default)
			)
			(layer "F.Fab")
		)
		(pad "1" smd circle
			(at -0.40005 0)
			(size 0 0)
			(layers "F.Cu" "F.Mask" "F.Paste")
			(net "PEX2_PCA9555_INT_N")
		)
		(pad "2" smd circle
			(at 0.40005 0)
			(size 0 0)
			(layers "F.Cu" "F.Mask" "F.Paste")
			(net "PEX2_PCA9555_0_INT_N")
		)
	)
)
